(kicad_pcb
	(version 20260206)
	(generator "pcbnew")
	(generator_version "10.0")
	(general
		(thickness 1.6)
		(legacy_teardrops no)
	)
	(paper "A4")
	(title_block
		(title "03242023_DA0F0TMBIJ0_F0T_Motherboard_J_brd_V01_OCP.brd")
		(comment 1 "Grand Teton / footprints 651-651 of 6105")
	)
	(layers
		(0 "F.Cu" signal "TOP")
		(4 "In1.Cu" signal "GND")
		(6 "In2.Cu" signal "IN1")
		(8 "In3.Cu" signal "GND1")
		(10 "In4.Cu" signal "IN2")
		(12 "In5.Cu" signal "GND2")
		(14 "In6.Cu" signal "IN3")
		(16 "In7.Cu" signal "GND3")
		(18 "In8.Cu" signal "VCC")
		(20 "In9.Cu" signal "VCC1")
		(22 "In10.Cu" signal "GND4")
		(24 "In11.Cu" signal "IN4")
		(26 "In12.Cu" signal "GND5")
		(28 "In13.Cu" signal "IN5")
		(30 "In14.Cu" signal "GND6")
		(32 "In15.Cu" signal "IN6")
		(34 "In16.Cu" signal "GND7")
		(2 "B.Cu" signal "BOTTOM")
		(9 "F.Adhes" user "F.Adhesive")
		(11 "B.Adhes" user "B.Adhesive")
		(13 "F.Paste" user "Package Geometry/Pastemask Top")
		(15 "B.Paste" user "Package Geometry/Pastemask Bottom")
		(5 "F.SilkS" user "Ref Des/Silkscreen Top")
		(7 "B.SilkS" user "Ref Des/Silkscreen Bottom")
		(1 "F.Mask" user "Board Geometry/Soldermask Top")
		(3 "B.Mask" user "Board Geometry/Soldermask Bottom")
		(17 "Dwgs.User" user "User.Drawings")
		(19 "Cmts.User" user "User.Comments")
		(21 "Eco1.User" user "User.Eco1")
		(23 "Eco2.User" user "User.Eco2")
		(25 "Edge.Cuts" user "Board Geometry/Outline")
		(27 "Margin" user)
		(31 "F.CrtYd" user "Package Geometry/Place Bound Top")
		(29 "B.CrtYd" user "Package Geometry/Place Bound Bottom")
		(35 "F.Fab" user "Ref Des/Assembly Top")
		(33 "B.Fab" user "Ref Des/Assembly Bottom")
	)
	(footprint ""
		(layer "F.Cu")
		(at 317.396622 -61.331348 180)
		(property "Reference" "R1476"
			(at 0 0 180)
			(layer "F.SilkS")
			(hide yes)
			(effects
				(font
					(size 1.27 1.27)
				)
			)
		)
		(property "Value" ""
			(at 0 0 180)
			(layer "F.Fab")
			(effects
				(font
					(size 1.27 1.27)
				)
			)
		)
		(duplicate_pad_numbers_are_jumpers no)
		(fp_line
			(start 0.7874 0.4064)
			(end -0.7874 0.4064)
			(stroke
				(width 0.1524)
				(type default)
			)
			(layer "F.SilkS")
		)
		(fp_line
			(start 0.7874 -0.4064)
			(end 0.7874 0.4064)
			(stroke
				(width 0.1524)
				(type default)
			)
			(layer "F.SilkS")
		)
		(fp_line
			(start -0.7874 0.4064)
			(end -0.7874 -0.4064)
			(stroke
				(width 0.1524)
				(type default)
			)
			(layer "F.SilkS")
		)
		(fp_line
			(start -0.7874 -0.4064)
			(end 0.7874 -0.4064)
			(stroke
				(width 0.1524)
				(type default)
			)
			(layer "F.SilkS")
		)
		(fp_line
			(start 0.67945 0.3048)
			(end 0.120396 0.3048)
			(stroke
				(width 0.1)
				(type default)
			)
			(layer "F.Fab")
		)
		(fp_line
			(start 0.67945 -0.3048)
			(end 0.67945 0.3048)
			(stroke
				(width 0.1)
				(type default)
			)
			(layer "F.Fab")
		)
		(fp_line
			(start 0.12065 -0.2794)
			(end 0.12065 -0.3048)
			(stroke
				(width 0.1)
				(type default)
			)
			(layer "F.Fab")
		)
		(fp_line
			(start 0.12065 -0.3048)
			(end 0.67945 -0.3048)
			(stroke
				(width 0.1)
				(type default)
			)
			(layer "F.Fab")
		)
		(fp_line
			(start 0.120396 0.3048)
			(end 0.120396 0.2794)
			(stroke
				(width 0.1)
				(type default)
			)
			(layer "F.Fab")
		)
		(fp_line
			(start 0.120396 0.2794)
			(end -0.12065 0.2794)
			(stroke
				(width 0.1)
				(type default)
			)
			(layer "F.Fab")
		)
		(fp_line
			(start -0.12065 0.3048)
			(end -0.67945 0.3048)
			(stroke
				(width 0.1)
				(type default)
			)
			(layer "F.Fab")
		)
		(fp_line
			(start -0.12065 0.2794)
			(end -0.12065 0.3048)
			(stroke
				(width 0.1)
				(type default)
			)
			(layer "F.Fab")
		)
		(fp_line
			(start -0.12065 -0.2794)
			(end 0.12065 -0.2794)
			(stroke
				(width 0.1)
				(type default)
			)
			(layer "F.Fab")
		)
		(fp_line
			(start -0.12065 -0.305054)
			(end -0.12065 -0.2794)
			(stroke
				(width 0.1)
				(type default)
			)
			(layer "F.Fab")
		)
		(fp_line
			(start -0.67945 0.3048)
			(end -0.67945 -0.305054)
			(stroke
				(width 0.1)
				(type default)
			)
			(layer "F.Fab")
		)
		(fp_line
			(start -0.67945 -0.305054)
			(end -0.12065 -0.305054)
			(stroke
				(width 0.1)
				(type default)
			)
			(layer "F.Fab")
		)
		(pad "1" smd circle
			(at -0.40005 0 180)
			(size 0 0)
			(layers "F.Cu" "F.Mask" "F.Paste")
			(net "FM_PCH_RING_OSC_BYPASS_MGPIO_TE")
		)
		(pad "2" smd circle
			(at 0.40005 0 180)
			(size 0 0)
			(layers "F.Cu" "F.Mask" "F.Paste")
			(net "GND")
		)
	)
)
